(kicad_pcb
	(version 20260206)
	(generator "pcbnew")
	(generator_version "10.0")
	(general
		(thickness 1.6)
		(legacy_teardrops no)
	)
	(paper "A4")
	(title_block
		(title "01162023_DA0F0TEBIF0_F0T_Expander_BD_F_brd_V02_OCP.brd")
		(comment 1 "Grand Teton / footprints 4621-4627 of 9728")
	)
	(layers
		(0 "F.Cu" signal "TOP")
		(4 "In1.Cu" signal "GND")
		(6 "In2.Cu" signal "VCC")
		(8 "In3.Cu" signal "VCC1")
		(10 "In4.Cu" signal "GND1")
		(12 "In5.Cu" signal "IN1")
		(14 "In6.Cu" signal "GND2")
		(16 "In7.Cu" signal "IN2")
		(18 "In8.Cu" signal "GND3")
		(20 "In9.Cu" signal "IN3")
		(22 "In10.Cu" signal "GND4")
		(24 "In11.Cu" signal "IN4")
		(26 "In12.Cu" signal "GND5")
		(28 "In13.Cu" signal "IN5")
		(30 "In14.Cu" signal "GND6")
		(32 "In15.Cu" signal "IN6")
		(34 "In16.Cu" signal "GND7")
		(2 "B.Cu" signal "BOTTOM")
		(9 "F.Adhes" user "F.Adhesive")
		(11 "B.Adhes" user "B.Adhesive")
		(13 "F.Paste" user "Package Geometry/Pastemask Top")
		(15 "B.Paste" user "Package Geometry/Pastemask Bottom")
		(5 "F.SilkS" user "Ref Des/Silkscreen Top")
		(7 "B.SilkS" user "Ref Des/Silkscreen Bottom")
		(1 "F.Mask" user "Board Geometry/Soldermask Top")
		(3 "B.Mask" user "Board Geometry/Soldermask Bottom")
		(17 "Dwgs.User" user "User.Drawings")
		(19 "Cmts.User" user "User.Comments")
		(21 "Eco1.User" user "User.Eco1")
		(23 "Eco2.User" user "User.Eco2")
		(25 "Edge.Cuts" user "Board Geometry/Outline")
		(27 "Margin" user)
		(31 "F.CrtYd" user "Package Geometry/Place Bound Top")
		(29 "B.CrtYd" user "Package Geometry/Place Bound Bottom")
		(35 "F.Fab" user "Ref Des/Assembly Top")
		(33 "B.Fab" user "Ref Des/Assembly Bottom")
	)
	(footprint ""
		(layer "F.Cu")
		(at 257.262376 -22.955504 -90)
		(property "Reference" "C2727"
			(at 0 0 270)
			(layer "F.SilkS")
			(hide yes)
			(effects
				(font
					(size 1.27 1.27)
				)
			)
		)
		(property "Value" ""
			(at 0 0 270)
			(layer "F.Fab")
			(effects
				(font
					(size 1.27 1.27)
				)
			)
		)
		(duplicate_pad_numbers_are_jumpers no)
		(fp_line
			(start -0.7874 0.4064)
			(end -0.7874 -0.4064)
			(stroke
				(width 0.1524)
				(type default)
			)
			(layer "F.SilkS")
		)
		(fp_line
			(start 0.7874 0.4064)
			(end -0.7874 0.4064)
			(stroke
				(width 0.1524)
				(type default)
			)
			(layer "F.SilkS")
		)
		(fp_line
			(start -0.7874 -0.4064)
			(end 0.7874 -0.4064)
			(stroke
				(width 0.1524)
				(type default)
			)
			(layer "F.SilkS")
		)
		(fp_line
			(start 0.7874 -0.4064)
			(end 0.7874 0.4064)
			(stroke
				(width 0.1524)
				(type default)
			)
			(layer "F.SilkS")
		)
		(fp_line
			(start -0.67945 0.3048)
			(end -0.67945 -0.305054)
			(stroke
				(width 0.1)
				(type default)
			)
			(layer "F.Fab")
		)
		(fp_line
			(start -0.12065 0.3048)
			(end -0.67945 0.3048)
			(stroke
				(width 0.1)
				(type default)
			)
			(layer "F.Fab")
		)
		(fp_line
			(start 0.120396 0.3048)
			(end 0.120396 0.2794)
			(stroke
				(width 0.1)
				(type default)
			)
			(layer "F.Fab")
		)
		(fp_line
			(start 0.67945 0.3048)
			(end 0.120396 0.3048)
			(stroke
				(width 0.1)
				(type default)
			)
			(layer "F.Fab")
		)
		(fp_line
			(start -0.12065 0.2794)
			(end -0.12065 0.3048)
			(stroke
				(width 0.1)
				(type default)
			)
			(layer "F.Fab")
		)
		(fp_line
			(start 0.120396 0.2794)
			(end -0.12065 0.2794)
			(stroke
				(width 0.1)
				(type default)
			)
			(layer "F.Fab")
		)
		(fp_line
			(start -0.12065 -0.2794)
			(end 0.12065 -0.2794)
			(stroke
				(width 0.1)
				(type default)
			)
			(layer "F.Fab")
		)
		(fp_line
			(start 0.12065 -0.2794)
			(end 0.12065 -0.3048)
			(stroke
				(width 0.1)
				(type default)
			)
			(layer "F.Fab")
		)
		(fp_line
			(start 0.12065 -0.3048)
			(end 0.67945 -0.3048)
			(stroke
				(width 0.1)
				(type default)
			)
			(layer "F.Fab")
		)
		(fp_line
			(start 0.67945 -0.3048)
			(end 0.67945 0.3048)
			(stroke
				(width 0.1)
				(type default)
			)
			(layer "F.Fab")
		)
		(fp_line
			(start -0.67945 -0.305054)
			(end -0.12065 -0.305054)
			(stroke
				(width 0.1)
				(type default)
			)
			(layer "F.Fab")
		)
		(fp_line
			(start -0.12065 -0.305054)
			(end -0.12065 -0.2794)
			(stroke
				(width 0.1)
				(type default)
			)
			(layer "F.Fab")
		)
		(pad "1" smd circle
			(at -0.40005 0 270)
			(size 0 0)
			(layers "F.Cu" "F.Mask" "F.Paste")
			(net "GND")
		)
		(pad "2" smd circle
			(at 0.40005 0 270)
			(size 0 0)
			(layers "F.Cu" "F.Mask" "F.Paste")
			(net "P3V3_AUX")
		)
	)
	(footprint ""
		(layer "F.Cu")
		(at 353.168966 -280.44902 -90)
		(property "Reference" "PC179"
			(at 0 0 270)
			(layer "F.SilkS")
			(hide yes)
			(effects
				(font
					(size 1.27 1.27)
				)
			)
		)
		(property "Value" ""
			(at 0 0 270)
			(layer "F.Fab")
			(effects
				(font
					(size 1.27 1.27)
				)
			)
		)
		(duplicate_pad_numbers_are_jumpers no)
		(fp_line
			(start -0.7874 0.4064)
			(end -0.7874 -0.4064)
			(stroke
				(width 0.1524)
				(type default)
			)
			(layer "F.SilkS")
		)
		(fp_line
			(start 0.7874 0.4064)
			(end -0.7874 0.4064)
			(stroke
				(width 0.1524)
				(type default)
			)
			(layer "F.SilkS")
		)
		(fp_line
			(start -0.7874 -0.4064)
			(end 0.7874 -0.4064)
			(stroke
				(width 0.1524)
				(type default)
			)
			(layer "F.SilkS")
		)
		(fp_line
			(start 0.7874 -0.4064)
			(end 0.7874 0.4064)
			(stroke
				(width 0.1524)
				(type default)
			)
			(layer "F.SilkS")
		)
		(fp_line
			(start -0.67945 0.3048)
			(end -0.67945 -0.305054)
			(stroke
				(width 0.1)
				(type default)
			)
			(layer "F.Fab")
		)
		(fp_line
			(start -0.12065 0.3048)
			(end -0.67945 0.3048)
			(stroke
				(width 0.1)
				(type default)
			)
			(layer "F.Fab")
		)
		(fp_line
			(start 0.120396 0.3048)
			(end 0.120396 0.2794)
			(stroke
				(width 0.1)
				(type default)
			)
			(layer "F.Fab")
		)
		(fp_line
			(start 0.67945 0.3048)
			(end 0.120396 0.3048)
			(stroke
				(width 0.1)
				(type default)
			)
			(layer "F.Fab")
		)
		(fp_line
			(start -0.12065 0.2794)
			(end -0.12065 0.3048)
			(stroke
				(width 0.1)
				(type default)
			)
			(layer "F.Fab")
		)
		(fp_line
			(start 0.120396 0.2794)
			(end -0.12065 0.2794)
			(stroke
				(width 0.1)
				(type default)
			)
			(layer "F.Fab")
		)
		(fp_line
			(start -0.12065 -0.2794)
			(end 0.12065 -0.2794)
			(stroke
				(width 0.1)
				(type default)
			)
			(layer "F.Fab")
		)
		(fp_line
			(start 0.12065 -0.2794)
			(end 0.12065 -0.3048)
			(stroke
				(width 0.1)
				(type default)
			)
			(layer "F.Fab")
		)
		(fp_line
			(start 0.12065 -0.3048)
			(end 0.67945 -0.3048)
			(stroke
				(width 0.1)
				(type default)
			)
			(layer "F.Fab")
		)
		(fp_line
			(start 0.67945 -0.3048)
			(end 0.67945 0.3048)
			(stroke
				(width 0.1)
				(type default)
			)
			(layer "F.Fab")
		)
		(fp_line
			(start -0.67945 -0.305054)
			(end -0.12065 -0.305054)
			(stroke
				(width 0.1)
				(type default)
			)
			(layer "F.Fab")
		)
		(fp_line
			(start -0.12065 -0.305054)
			(end -0.12065 -0.2794)
			(stroke
				(width 0.1)
				(type default)
			)
			(layer "F.Fab")
		)
		(pad "1" smd circle
			(at -0.40005 0 270)
			(size 0 0)
			(layers "F.Cu" "F.Mask" "F.Paste")
			(net "SW_P0V8_PEX3_PHASE1")
		)
		(pad "2" smd circle
			(at 0.40005 0 270)
			(size 0 0)
			(layers "F.Cu" "F.Mask" "F.Paste")
			(net "SW_P0V8_PEX3_BOOT1_R")
		)
	)
	(footprint ""
		(layer "F.Cu")
		(at 187.896246 -47.20082 90)
		(property "Reference" "C316"
			(at 0 0 90)
			(layer "F.SilkS")
			(hide yes)
			(effects
				(font
					(size 1.27 1.27)
				)
			)
		)
		(property "Value" ""
			(at 0 0 90)
			(layer "F.Fab")
			(effects
				(font
					(size 1.27 1.27)
				)
			)
		)
		(duplicate_pad_numbers_are_jumpers no)
		(fp_line
			(start 0.7874 -0.4064)
			(end 0.7874 0.4064)
			(stroke
				(width 0.1524)
				(type default)
			)
			(layer "F.SilkS")
		)
		(fp_line
			(start -0.7874 -0.4064)
			(end 0.7874 -0.4064)
			(stroke
				(width 0.1524)
				(type default)
			)
			(layer "F.SilkS")
		)
		(fp_line
			(start 0.7874 0.4064)
			(end -0.7874 0.4064)
			(stroke
				(width 0.1524)
				(type default)
			)
			(layer "F.SilkS")
		)
		(fp_line
			(start -0.7874 0.4064)
			(end -0.7874 -0.4064)
			(stroke
				(width 0.1524)
				(type default)
			)
			(layer "F.SilkS")
		)
		(fp_line
			(start -0.12065 -0.305054)
			(end -0.12065 -0.2794)
			(stroke
				(width 0.1)
				(type default)
			)
			(layer "F.Fab")
		)
		(fp_line
			(start -0.67945 -0.305054)
			(end -0.12065 -0.305054)
			(stroke
				(width 0.1)
				(type default)
			)
			(layer "F.Fab")
		)
		(fp_line
			(start 0.67945 -0.3048)
			(end 0.67945 0.3048)
			(stroke
				(width 0.1)
				(type default)
			)
			(layer "F.Fab")
		)
		(fp_line
			(start 0.12065 -0.3048)
			(end 0.67945 -0.3048)
			(stroke
				(width 0.1)
				(type default)
			)
			(layer "F.Fab")
		)
		(fp_line
			(start 0.12065 -0.2794)
			(end 0.12065 -0.3048)
			(stroke
				(width 0.1)
				(type default)
			)
			(layer "F.Fab")
		)
		(fp_line
			(start -0.12065 -0.2794)
			(end 0.12065 -0.2794)
			(stroke
				(width 0.1)
				(type default)
			)
			(layer "F.Fab")
		)
		(fp_line
			(start 0.120396 0.2794)
			(end -0.12065 0.2794)
			(stroke
				(width 0.1)
				(type default)
			)
			(layer "F.Fab")
		)
		(fp_line
			(start -0.12065 0.2794)
			(end -0.12065 0.3048)
			(stroke
				(width 0.1)
				(type default)
			)
			(layer "F.Fab")
		)
		(fp_line
			(start 0.67945 0.3048)
			(end 0.120396 0.3048)
			(stroke
				(width 0.1)
				(type default)
			)
			(layer "F.Fab")
		)
		(fp_line
			(start 0.120396 0.3048)
			(end 0.120396 0.2794)
			(stroke
				(width 0.1)
				(type default)
			)
			(layer "F.Fab")
		)
		(fp_line
			(start -0.12065 0.3048)
			(end -0.67945 0.3048)
			(stroke
				(width 0.1)
				(type default)
			)
			(layer "F.Fab")
		)
		(fp_line
			(start -0.67945 0.3048)
			(end -0.67945 -0.305054)
			(stroke
				(width 0.1)
				(type default)
			)
			(layer "F.Fab")
		)
		(pad "1" smd circle
			(at -0.40005 0 90)
			(size 0 0)
			(layers "F.Cu" "F.Mask" "F.Paste")
			(net "P12V_SSD6_R")
		)
		(pad "2" smd circle
			(at 0.40005 0 90)
			(size 0 0)
			(layers "F.Cu" "F.Mask" "F.Paste")
			(net "GND")
		)
	)
	(footprint ""
		(layer "F.Cu")
		(at 325.827644 -343.952322 90)
		(property "Reference" "C562"
			(at 0 0 90)
			(layer "F.SilkS")
			(hide yes)
			(effects
				(font
					(size 1.27 1.27)
				)
			)
		)
		(property "Value" ""
			(at 0 0 90)
			(layer "F.Fab")
			(effects
				(font
					(size 1.27 1.27)
				)
			)
		)
		(duplicate_pad_numbers_are_jumpers no)
		(fp_line
			(start 0.299974 -0.150114)
			(end 0.299974 0.150114)
			(stroke
				(width 0.1)
				(type default)
			)
			(layer "F.Fab")
		)
		(fp_line
			(start -0.299974 -0.150114)
			(end 0.299974 -0.150114)
			(stroke
				(width 0.1)
				(type default)
			)
			(layer "F.Fab")
		)
		(fp_line
			(start 0.299974 0.150114)
			(end -0.299974 0.150114)
			(stroke
				(width 0.1)
				(type default)
			)
			(layer "F.Fab")
		)
		(fp_line
			(start -0.299974 0.150114)
			(end -0.299974 -0.150114)
			(stroke
				(width 0.1)
				(type default)
			)
			(layer "F.Fab")
		)
		(pad "1" smd rect
			(at -0.2667 0 90)
			(size 0.3048 0.381)
			(layers "F.Cu" "F.Mask" "F.Paste")
			(net "P5E_PEX2_STN6_TX_DN<106>")
		)
		(pad "2" smd rect
			(at 0.2667 0 90)
			(size 0.3048 0.381)
			(layers "F.Cu" "F.Mask" "F.Paste")
			(net "P5E_PEX2_STN6_TX_C_DN<106>")
		)
	)
	(footprint ""
		(layer "F.Cu")
		(at 203.792582 -303.913794 90)
		(property "Reference" "R6717"
			(at 0 0 90)
			(layer "F.SilkS")
			(hide yes)
			(effects
				(font
					(size 1.27 1.27)
				)
			)
		)
		(property "Value" ""
			(at 0 0 90)
			(layer "F.Fab")
			(effects
				(font
					(size 1.27 1.27)
				)
			)
		)
		(duplicate_pad_numbers_are_jumpers no)
		(fp_line
			(start 0.7874 -0.4064)
			(end 0.7874 0.4064)
			(stroke
				(width 0.1524)
				(type default)
			)
			(layer "F.SilkS")
		)
		(fp_line
			(start -0.7874 -0.4064)
			(end 0.7874 -0.4064)
			(stroke
				(width 0.1524)
				(type default)
			)
			(layer "F.SilkS")
		)
		(fp_line
			(start 0.7874 0.4064)
			(end -0.7874 0.4064)
			(stroke
				(width 0.1524)
				(type default)
			)
			(layer "F.SilkS")
		)
		(fp_line
			(start -0.7874 0.4064)
			(end -0.7874 -0.4064)
			(stroke
				(width 0.1524)
				(type default)
			)
			(layer "F.SilkS")
		)
		(fp_line
			(start -0.12065 -0.305054)
			(end -0.12065 -0.2794)
			(stroke
				(width 0.1)
				(type default)
			)
			(layer "F.Fab")
		)
		(fp_line
			(start -0.67945 -0.305054)
			(end -0.12065 -0.305054)
			(stroke
				(width 0.1)
				(type default)
			)
			(layer "F.Fab")
		)
		(fp_line
			(start 0.67945 -0.3048)
			(end 0.67945 0.3048)
			(stroke
				(width 0.1)
				(type default)
			)
			(layer "F.Fab")
		)
		(fp_line
			(start 0.12065 -0.3048)
			(end 0.67945 -0.3048)
			(stroke
				(width 0.1)
				(type default)
			)
			(layer "F.Fab")
		)
		(fp_line
			(start 0.12065 -0.2794)
			(end 0.12065 -0.3048)
			(stroke
				(width 0.1)
				(type default)
			)
			(layer "F.Fab")
		)
		(fp_line
			(start -0.12065 -0.2794)
			(end 0.12065 -0.2794)
			(stroke
				(width 0.1)
				(type default)
			)
			(layer "F.Fab")
		)
		(fp_line
			(start 0.120396 0.2794)
			(end -0.12065 0.2794)
			(stroke
				(width 0.1)
				(type default)
			)
			(layer "F.Fab")
		)
		(fp_line
			(start -0.12065 0.2794)
			(end -0.12065 0.3048)
			(stroke
				(width 0.1)
				(type default)
			)
			(layer "F.Fab")
		)
		(fp_line
			(start 0.67945 0.3048)
			(end 0.120396 0.3048)
			(stroke
				(width 0.1)
				(type default)
			)
			(layer "F.Fab")
		)
		(fp_line
			(start 0.120396 0.3048)
			(end 0.120396 0.2794)
			(stroke
				(width 0.1)
				(type default)
			)
			(layer "F.Fab")
		)
		(fp_line
			(start -0.12065 0.3048)
			(end -0.67945 0.3048)
			(stroke
				(width 0.1)
				(type default)
			)
			(layer "F.Fab")
		)
		(fp_line
			(start -0.67945 0.3048)
			(end -0.67945 -0.305054)
			(stroke
				(width 0.1)
				(type default)
			)
			(layer "F.Fab")
		)
		(pad "1" smd circle
			(at -0.40005 0 90)
			(size 0 0)
			(layers "F.Cu" "F.Mask" "F.Paste")
			(net "SMB_PEX1_SLAVE1_SDA")
		)
		(pad "2" smd circle
			(at 0.40005 0 90)
			(size 0 0)
			(layers "F.Cu" "F.Mask" "F.Paste")
			(net "SMB_PEX1_R_SDA")
		)
	)
	(footprint ""
		(layer "F.Cu")
		(at 257.541776 -261.026402 180)
		(property "Reference" "C3418"
			(at 0 0 180)
			(layer "F.SilkS")
			(hide yes)
			(effects
				(font
					(size 1.27 1.27)
				)
			)
		)
		(property "Value" ""
			(at 0 0 180)
			(layer "F.Fab")
			(effects
				(font
					(size 1.27 1.27)
				)
			)
		)
		(duplicate_pad_numbers_are_jumpers no)
		(fp_line
			(start 1.2954 0.5842)
			(end -1.2954 0.5842)
			(stroke
				(width 0.1524)
				(type default)
			)
			(layer "F.SilkS")
		)
		(fp_line
			(start 1.2954 -0.5842)
			(end 1.2954 0.5842)
			(stroke
				(width 0.1524)
				(type default)
			)
			(layer "F.SilkS")
		)
		(fp_line
			(start -1.2954 0.5842)
			(end -1.2954 -0.5842)
			(stroke
				(width 0.1524)
				(type default)
			)
			(layer "F.SilkS")
		)
		(fp_line
			(start -1.2954 -0.5842)
			(end 1.2954 -0.5842)
			(stroke
				(width 0.1524)
				(type default)
			)
			(layer "F.SilkS")
		)
		(fp_line
			(start 1.1938 0.4064)
			(end 0.8636 0.4064)
			(stroke
				(width 0.1)
				(type default)
			)
			(layer "F.Fab")
		)
		(fp_line
			(start 1.1938 -0.4064)
			(end 1.1938 0.4064)
			(stroke
				(width 0.1)
				(type default)
			)
			(layer "F.Fab")
		)
		(fp_line
			(start 0.8636 0.4572)
			(end -0.8636 0.4572)
			(stroke
				(width 0.1)
				(type default)
			)
			(layer "F.Fab")
		)
		(fp_line
			(start 0.8636 0.4064)
			(end 0.8636 0.4572)
			(stroke
				(width 0.1)
				(type default)
			)
			(layer "F.Fab")
		)
		(fp_line
			(start 0.8636 -0.4064)
			(end 1.1938 -0.4064)
			(stroke
				(width 0.1)
				(type default)
			)
			(layer "F.Fab")
		)
		(fp_line
			(start 0.8636 -0.4572)
			(end 0.8636 -0.4064)
			(stroke
				(width 0.1)
				(type default)
			)
			(layer "F.Fab")
		)
		(fp_line
			(start -0.8636 0.4572)
			(end -0.8636 0.4064)
			(stroke
				(width 0.1)
				(type default)
			)
			(layer "F.Fab")
		)
		(fp_line
			(start -0.8636 0.4064)
			(end -1.1938 0.4064)
			(stroke
				(width 0.1)
				(type default)
			)
			(layer "F.Fab")
		)
		(fp_line
			(start -0.8636 -0.4064)
			(end -0.8636 -0.4572)
			(stroke
				(width 0.1)
				(type default)
			)
			(layer "F.Fab")
		)
		(fp_line
			(start -0.8636 -0.4572)
			(end 0.8636 -0.4572)
			(stroke
				(width 0.1)
				(type default)
			)
			(layer "F.Fab")
		)
		(fp_line
			(start -1.1938 0.4064)
			(end -1.1938 -0.4064)
			(stroke
				(width 0.1)
				(type default)
			)
			(layer "F.Fab")
		)
		(fp_line
			(start -1.1938 -0.4064)
			(end -0.8636 -0.4064)
			(stroke
				(width 0.1)
				(type default)
			)
			(layer "F.Fab")
		)
		(pad "1" smd rect
			(at -0.7366 0 90)
			(size 0.7112 0.8128)
			(layers "F.Cu" "F.Mask" "F.Paste")
			(net "P1V8_VDDA_PEX2")
		)
		(pad "2" smd rect
			(at 0.7366 0 90)
			(size 0.7112 0.8128)
			(layers "F.Cu" "F.Mask" "F.Paste")
			(net "GND")
		)
	)
	(footprint ""
		(layer "F.Cu")
		(at 310.467756 -53.051456)
		(property "Reference" "R4470"
			(at 0 0 0)
			(layer "F.SilkS")
			(hide yes)
			(effects
				(font
					(size 1.27 1.27)
				)
			)
		)
		(property "Value" ""
			(at 0 0 0)
			(layer "F.Fab")
			(effects
				(font
					(size 1.27 1.27)
				)
			)
		)
		(duplicate_pad_numbers_are_jumpers no)
		(fp_line
			(start -0.7874 -0.4064)
			(end 0.7874 -0.4064)
			(stroke
				(width 0.1524)
				(type default)
			)
			(layer "F.SilkS")
		)
		(fp_line
			(start -0.7874 0.4064)
			(end -0.7874 -0.4064)
			(stroke
				(width 0.1524)
				(type default)
			)
			(layer "F.SilkS")
		)
		(fp_line
			(start 0.7874 -0.4064)
			(end 0.7874 0.4064)
			(stroke
				(width 0.1524)
				(type default)
			)
			(layer "F.SilkS")
		)
		(fp_line
			(start 0.7874 0.4064)
			(end -0.7874 0.4064)
			(stroke
				(width 0.1524)
				(type default)
			)
			(layer "F.SilkS")
		)
		(fp_line
			(start -0.67945 -0.305054)
			(end -0.12065 -0.305054)
			(stroke
				(width 0.1)
				(type default)
			)
			(layer "F.Fab")
		)
		(fp_line
			(start -0.67945 0.3048)
			(end -0.67945 -0.305054)
			(stroke
				(width 0.1)
				(type default)
			)
			(layer "F.Fab")
		)
		(fp_line
			(start -0.12065 -0.305054)
			(end -0.12065 -0.2794)
			(stroke
				(width 0.1)
				(type default)
			)
			(layer "F.Fab")
		)
		(fp_line
			(start -0.12065 -0.2794)
			(end 0.12065 -0.2794)
			(stroke
				(width 0.1)
				(type default)
			)
			(layer "F.Fab")
		)
		(fp_line
			(start -0.12065 0.2794)
			(end -0.12065 0.3048)
			(stroke
				(width 0.1)
				(type default)
			)
			(layer "F.Fab")
		)
		(fp_line
			(start -0.12065 0.3048)
			(end -0.67945 0.3048)
			(stroke
				(width 0.1)
				(type default)
			)
			(layer "F.Fab")
		)
		(fp_line
			(start 0.120396 0.2794)
			(end -0.12065 0.2794)
			(stroke
				(width 0.1)
				(type default)
			)
			(layer "F.Fab")
		)
		(fp_line
			(start 0.120396 0.3048)
			(end 0.120396 0.2794)
			(stroke
				(width 0.1)
				(type default)
			)
			(layer "F.Fab")
		)
		(fp_line
			(start 0.12065 -0.3048)
			(end 0.67945 -0.3048)
			(stroke
				(width 0.1)
				(type default)
			)
			(layer "F.Fab")
		)
		(fp_line
			(start 0.12065 -0.2794)
			(end 0.12065 -0.3048)
			(stroke
				(width 0.1)
				(type default)
			)
			(layer "F.Fab")
		)
		(fp_line
			(start 0.67945 -0.3048)
			(end 0.67945 0.3048)
			(stroke
				(width 0.1)
				(type default)
			)
			(layer "F.Fab")
		)
		(fp_line
			(start 0.67945 0.3048)
			(end 0.120396 0.3048)
			(stroke
				(width 0.1)
				(type default)
			)
			(layer "F.Fab")
		)
		(pad "1" smd circle
			(at -0.40005 0)
			(size 0 0)
			(layers "F.Cu" "F.Mask" "F.Paste")
			(net "PWRGD_P12V_SSD10")
		)
		(pad "2" smd circle
			(at 0.40005 0)
			(size 0 0)
			(layers "F.Cu" "F.Mask" "F.Paste")
			(net "PWRGD_P12V_SSD10_R")
		)
	)
)
